(kicad_pcb
	(version 20260206)
	(generator "pcbnew")
	(generator_version "10.0")
	(general
		(thickness 1.6)
		(legacy_teardrops no)
	)
	(paper "A4")
	(title_block
		(title "04192023_DAF0TMB3IC0_F0TG_MB_C_brd_V02_OCP.brd")
		(comment 1 "Grand Teton / footprints 3741-3748 of 8354")
	)
	(layers
		(0 "F.Cu" signal "TOP")
		(4 "In1.Cu" signal "GND")
		(6 "In2.Cu" signal "IN1")
		(8 "In3.Cu" signal "GND1")
		(10 "In4.Cu" signal "IN2")
		(12 "In5.Cu" signal "GND2")
		(14 "In6.Cu" signal "IN3")
		(16 "In7.Cu" signal "GND3")
		(18 "In8.Cu" signal "VCC")
		(20 "In9.Cu" signal "VCC1")
		(22 "In10.Cu" signal "GND4")
		(24 "In11.Cu" signal "IN4")
		(26 "In12.Cu" signal "GND5")
		(28 "In13.Cu" signal "IN5")
		(30 "In14.Cu" signal "GND6")
		(32 "In15.Cu" signal "IN6")
		(34 "In16.Cu" signal "GND7")
		(2 "B.Cu" signal "BOTTOM")
		(9 "F.Adhes" user "F.Adhesive")
		(11 "B.Adhes" user "B.Adhesive")
		(13 "F.Paste" user "Package Geometry/Pastemask Top")
		(15 "B.Paste" user "Package Geometry/Pastemask Bottom")
		(5 "F.SilkS" user "Ref Des/Silkscreen Top")
		(7 "B.SilkS" user "Ref Des/Silkscreen Bottom")
		(1 "F.Mask" user "Board Geometry/Soldermask Top")
		(3 "B.Mask" user "Board Geometry/Soldermask Bottom")
		(17 "Dwgs.User" user "User.Drawings")
		(19 "Cmts.User" user "User.Comments")
		(21 "Eco1.User" user "User.Eco1")
		(23 "Eco2.User" user "User.Eco2")
		(25 "Edge.Cuts" user "Board Geometry/Outline")
		(27 "Margin" user)
		(31 "F.CrtYd" user "Package Geometry/Place Bound Top")
		(29 "B.CrtYd" user "Package Geometry/Place Bound Bottom")
		(35 "F.Fab" user "Ref Des/Assembly Top")
		(33 "B.Fab" user "Ref Des/Assembly Bottom")
	)
	(footprint ""
		(layer "F.Cu")
		(at 332.365096 -339.831172 90)
		(property "Reference" "PC84_1"
			(at 0 0 90)
			(layer "F.SilkS")
			(hide yes)
			(effects
				(font
					(size 1.27 1.27)
				)
			)
		)
		(property "Value" ""
			(at 0 0 90)
			(layer "F.Fab")
			(effects
				(font
					(size 1.27 1.27)
				)
			)
		)
		(duplicate_pad_numbers_are_jumpers no)
		(fp_line
			(start 0.7874 -0.4064)
			(end 0.7874 0.4064)
			(stroke
				(width 0.1524)
				(type default)
			)
			(layer "F.SilkS")
		)
		(fp_line
			(start -0.7874 -0.4064)
			(end 0.7874 -0.4064)
			(stroke
				(width 0.1524)
				(type default)
			)
			(layer "F.SilkS")
		)
		(fp_line
			(start 0.7874 0.4064)
			(end -0.7874 0.4064)
			(stroke
				(width 0.1524)
				(type default)
			)
			(layer "F.SilkS")
		)
		(fp_line
			(start -0.7874 0.4064)
			(end -0.7874 -0.4064)
			(stroke
				(width 0.1524)
				(type default)
			)
			(layer "F.SilkS")
		)
		(fp_line
			(start -0.12065 -0.305054)
			(end -0.12065 -0.2794)
			(stroke
				(width 0.1)
				(type default)
			)
			(layer "F.Fab")
		)
		(fp_line
			(start -0.67945 -0.305054)
			(end -0.12065 -0.305054)
			(stroke
				(width 0.1)
				(type default)
			)
			(layer "F.Fab")
		)
		(fp_line
			(start 0.67945 -0.3048)
			(end 0.67945 0.3048)
			(stroke
				(width 0.1)
				(type default)
			)
			(layer "F.Fab")
		)
		(fp_line
			(start 0.12065 -0.3048)
			(end 0.67945 -0.3048)
			(stroke
				(width 0.1)
				(type default)
			)
			(layer "F.Fab")
		)
		(fp_line
			(start 0.12065 -0.2794)
			(end 0.12065 -0.3048)
			(stroke
				(width 0.1)
				(type default)
			)
			(layer "F.Fab")
		)
		(fp_line
			(start -0.12065 -0.2794)
			(end 0.12065 -0.2794)
			(stroke
				(width 0.1)
				(type default)
			)
			(layer "F.Fab")
		)
		(fp_line
			(start 0.120396 0.2794)
			(end -0.12065 0.2794)
			(stroke
				(width 0.1)
				(type default)
			)
			(layer "F.Fab")
		)
		(fp_line
			(start -0.12065 0.2794)
			(end -0.12065 0.3048)
			(stroke
				(width 0.1)
				(type default)
			)
			(layer "F.Fab")
		)
		(fp_line
			(start 0.67945 0.3048)
			(end 0.120396 0.3048)
			(stroke
				(width 0.1)
				(type default)
			)
			(layer "F.Fab")
		)
		(fp_line
			(start 0.120396 0.3048)
			(end 0.120396 0.2794)
			(stroke
				(width 0.1)
				(type default)
			)
			(layer "F.Fab")
		)
		(fp_line
			(start -0.12065 0.3048)
			(end -0.67945 0.3048)
			(stroke
				(width 0.1)
				(type default)
			)
			(layer "F.Fab")
		)
		(fp_line
			(start -0.67945 0.3048)
			(end -0.67945 -0.305054)
			(stroke
				(width 0.1)
				(type default)
			)
			(layer "F.Fab")
		)
		(pad "1" smd circle
			(at -0.40005 0 90)
			(size 0 0)
			(layers "F.Cu" "F.Mask" "F.Paste")
			(net "PVDDCR_CPU1_P0_VCCS")
		)
		(pad "2" smd circle
			(at 0.40005 0 90)
			(size 0 0)
			(layers "F.Cu" "F.Mask" "F.Paste")
			(net "GND")
		)
	)
	(footprint ""
		(layer "F.Cu")
		(at 41.5544 -391.795)
		(property "Reference" "R726"
			(at 0 0 0)
			(layer "F.SilkS")
			(hide yes)
			(effects
				(font
					(size 1.27 1.27)
				)
			)
		)
		(property "Value" ""
			(at 0 0 0)
			(layer "F.Fab")
			(effects
				(font
					(size 1.27 1.27)
				)
			)
		)
		(duplicate_pad_numbers_are_jumpers no)
		(fp_line
			(start -0.32512 -0.175006)
			(end 0.32512 -0.175006)
			(stroke
				(width 0.1)
				(type default)
			)
			(layer "F.Fab")
		)
		(fp_line
			(start -0.32512 0.175006)
			(end -0.32512 -0.175006)
			(stroke
				(width 0.1)
				(type default)
			)
			(layer "F.Fab")
		)
		(fp_line
			(start 0.32512 -0.175006)
			(end 0.32512 0.175006)
			(stroke
				(width 0.1)
				(type default)
			)
			(layer "F.Fab")
		)
		(fp_line
			(start 0.32512 0.175006)
			(end -0.32512 0.175006)
			(stroke
				(width 0.1)
				(type default)
			)
			(layer "F.Fab")
		)
		(pad "1" smd rect
			(at -0.2667 0)
			(size 0.3048 0.381)
			(layers "F.Cu" "F.Mask" "F.Paste")
			(net "JTAG_TEST_MODE_RT_CPU1_P0")
		)
		(pad "2" smd rect
			(at 0.2667 0 180)
			(size 0.3048 0.381)
			(layers "F.Cu" "F.Mask" "F.Paste")
			(net "GND")
		)
	)
	(footprint ""
		(layer "F.Cu")
		(at 16.368268 -128.51511 -90)
		(property "Reference" "R4521"
			(at 0 0 270)
			(layer "F.SilkS")
			(hide yes)
			(effects
				(font
					(size 1.27 1.27)
				)
			)
		)
		(property "Value" ""
			(at 0 0 270)
			(layer "F.Fab")
			(effects
				(font
					(size 1.27 1.27)
				)
			)
		)
		(duplicate_pad_numbers_are_jumpers no)
		(fp_line
			(start -0.7874 0.4064)
			(end -0.7874 -0.4064)
			(stroke
				(width 0.1524)
				(type default)
			)
			(layer "F.SilkS")
		)
		(fp_line
			(start 0.7874 0.4064)
			(end -0.7874 0.4064)
			(stroke
				(width 0.1524)
				(type default)
			)
			(layer "F.SilkS")
		)
		(fp_line
			(start -0.7874 -0.4064)
			(end 0.7874 -0.4064)
			(stroke
				(width 0.1524)
				(type default)
			)
			(layer "F.SilkS")
		)
		(fp_line
			(start 0.7874 -0.4064)
			(end 0.7874 0.4064)
			(stroke
				(width 0.1524)
				(type default)
			)
			(layer "F.SilkS")
		)
		(fp_line
			(start -0.67945 0.3048)
			(end -0.67945 -0.305054)
			(stroke
				(width 0.1)
				(type default)
			)
			(layer "F.Fab")
		)
		(fp_line
			(start -0.12065 0.3048)
			(end -0.67945 0.3048)
			(stroke
				(width 0.1)
				(type default)
			)
			(layer "F.Fab")
		)
		(fp_line
			(start 0.120396 0.3048)
			(end 0.120396 0.2794)
			(stroke
				(width 0.1)
				(type default)
			)
			(layer "F.Fab")
		)
		(fp_line
			(start 0.67945 0.3048)
			(end 0.120396 0.3048)
			(stroke
				(width 0.1)
				(type default)
			)
			(layer "F.Fab")
		)
		(fp_line
			(start -0.12065 0.2794)
			(end -0.12065 0.3048)
			(stroke
				(width 0.1)
				(type default)
			)
			(layer "F.Fab")
		)
		(fp_line
			(start 0.120396 0.2794)
			(end -0.12065 0.2794)
			(stroke
				(width 0.1)
				(type default)
			)
			(layer "F.Fab")
		)
		(fp_line
			(start -0.12065 -0.2794)
			(end 0.12065 -0.2794)
			(stroke
				(width 0.1)
				(type default)
			)
			(layer "F.Fab")
		)
		(fp_line
			(start 0.12065 -0.2794)
			(end 0.12065 -0.3048)
			(stroke
				(width 0.1)
				(type default)
			)
			(layer "F.Fab")
		)
		(fp_line
			(start 0.12065 -0.3048)
			(end 0.67945 -0.3048)
			(stroke
				(width 0.1)
				(type default)
			)
			(layer "F.Fab")
		)
		(fp_line
			(start 0.67945 -0.3048)
			(end 0.67945 0.3048)
			(stroke
				(width 0.1)
				(type default)
			)
			(layer "F.Fab")
		)
		(fp_line
			(start -0.67945 -0.305054)
			(end -0.12065 -0.305054)
			(stroke
				(width 0.1)
				(type default)
			)
			(layer "F.Fab")
		)
		(fp_line
			(start -0.12065 -0.305054)
			(end -0.12065 -0.2794)
			(stroke
				(width 0.1)
				(type default)
			)
			(layer "F.Fab")
		)
		(pad "1" smd circle
			(at -0.40005 0 270)
			(size 0 0)
			(layers "F.Cu" "F.Mask" "F.Paste")
			(net "P3V3_AUX")
		)
		(pad "2" smd circle
			(at 0.40005 0 270)
			(size 0 0)
			(layers "F.Cu" "F.Mask" "F.Paste")
			(net "CLK_GEN2_BMC_RC_OE_N")
		)
	)
	(footprint ""
		(layer "F.Cu")
		(at 266.862306 -332.015846)
		(property "Reference" "TP5"
			(at -5.423916 0.05207 0)
			(unlocked yes)
			(layer "F.SilkS")
			(effects
				(font
					(size 0.7874 0.5842)
					(thickness 0.1524)
				)
				(justify left)
			)
		)
		(property "Value" ""
			(at 0 0 0)
			(layer "F.Fab")
			(effects
				(font
					(size 1.27 1.27)
				)
			)
		)
		(duplicate_pad_numbers_are_jumpers no)
		(pad "1" smd circle
			(at 0 0)
			(size 0.762 0.762)
			(layers "F.Cu" "F.Mask" "F.Paste")
			(net "VSENSE_PVDDIO_P0_DP")
		)
	)
	(footprint ""
		(layer "F.Cu")
		(at 430.277016 -101.97719 180)
		(property "Reference" "R3783"
			(at 0 0 180)
			(layer "F.SilkS")
			(hide yes)
			(effects
				(font
					(size 1.27 1.27)
				)
			)
		)
		(property "Value" ""
			(at 0 0 180)
			(layer "F.Fab")
			(effects
				(font
					(size 1.27 1.27)
				)
			)
		)
		(duplicate_pad_numbers_are_jumpers no)
		(fp_line
			(start 0.7874 0.4064)
			(end -0.7874 0.4064)
			(stroke
				(width 0.1524)
				(type default)
			)
			(layer "F.SilkS")
		)
		(fp_line
			(start 0.7874 -0.4064)
			(end 0.7874 0.4064)
			(stroke
				(width 0.1524)
				(type default)
			)
			(layer "F.SilkS")
		)
		(fp_line
			(start -0.7874 0.4064)
			(end -0.7874 -0.4064)
			(stroke
				(width 0.1524)
				(type default)
			)
			(layer "F.SilkS")
		)
		(fp_line
			(start -0.7874 -0.4064)
			(end 0.7874 -0.4064)
			(stroke
				(width 0.1524)
				(type default)
			)
			(layer "F.SilkS")
		)
		(fp_line
			(start 0.67945 0.3048)
			(end 0.120396 0.3048)
			(stroke
				(width 0.1)
				(type default)
			)
			(layer "F.Fab")
		)
		(fp_line
			(start 0.67945 -0.3048)
			(end 0.67945 0.3048)
			(stroke
				(width 0.1)
				(type default)
			)
			(layer "F.Fab")
		)
		(fp_line
			(start 0.12065 -0.2794)
			(end 0.12065 -0.3048)
			(stroke
				(width 0.1)
				(type default)
			)
			(layer "F.Fab")
		)
		(fp_line
			(start 0.12065 -0.3048)
			(end 0.67945 -0.3048)
			(stroke
				(width 0.1)
				(type default)
			)
			(layer "F.Fab")
		)
		(fp_line
			(start 0.120396 0.3048)
			(end 0.120396 0.2794)
			(stroke
				(width 0.1)
				(type default)
			)
			(layer "F.Fab")
		)
		(fp_line
			(start 0.120396 0.2794)
			(end -0.12065 0.2794)
			(stroke
				(width 0.1)
				(type default)
			)
			(layer "F.Fab")
		)
		(fp_line
			(start -0.12065 0.3048)
			(end -0.67945 0.3048)
			(stroke
				(width 0.1)
				(type default)
			)
			(layer "F.Fab")
		)
		(fp_line
			(start -0.12065 0.2794)
			(end -0.12065 0.3048)
			(stroke
				(width 0.1)
				(type default)
			)
			(layer "F.Fab")
		)
		(fp_line
			(start -0.12065 -0.2794)
			(end 0.12065 -0.2794)
			(stroke
				(width 0.1)
				(type default)
			)
			(layer "F.Fab")
		)
		(fp_line
			(start -0.12065 -0.305054)
			(end -0.12065 -0.2794)
			(stroke
				(width 0.1)
				(type default)
			)
			(layer "F.Fab")
		)
		(fp_line
			(start -0.67945 0.3048)
			(end -0.67945 -0.305054)
			(stroke
				(width 0.1)
				(type default)
			)
			(layer "F.Fab")
		)
		(fp_line
			(start -0.67945 -0.305054)
			(end -0.12065 -0.305054)
			(stroke
				(width 0.1)
				(type default)
			)
			(layer "F.Fab")
		)
		(pad "1" smd circle
			(at -0.40005 0 180)
			(size 0 0)
			(layers "F.Cu" "F.Mask" "F.Paste")
			(net "P3V3_AUX")
		)
		(pad "2" smd circle
			(at 0.40005 0 180)
			(size 0 0)
			(layers "F.Cu" "F.Mask" "F.Paste")
			(net "OCP_V3_1_P3V3_PWRGD")
		)
	)
	(footprint ""
		(layer "F.Cu")
		(at 331.494892 -390.77646 180)
		(property "Reference" "C965"
			(at 0 0 180)
			(layer "F.SilkS")
			(hide yes)
			(effects
				(font
					(size 1.27 1.27)
				)
			)
		)
		(property "Value" ""
			(at 0 0 180)
			(layer "F.Fab")
			(effects
				(font
					(size 1.27 1.27)
				)
			)
		)
		(duplicate_pad_numbers_are_jumpers no)
		(fp_line
			(start 0.299974 0.150114)
			(end -0.299974 0.150114)
			(stroke
				(width 0.1)
				(type default)
			)
			(layer "F.Fab")
		)
		(fp_line
			(start 0.299974 -0.150114)
			(end 0.299974 0.150114)
			(stroke
				(width 0.1)
				(type default)
			)
			(layer "F.Fab")
		)
		(fp_line
			(start -0.299974 0.150114)
			(end -0.299974 -0.150114)
			(stroke
				(width 0.1)
				(type default)
			)
			(layer "F.Fab")
		)
		(fp_line
			(start -0.299974 -0.150114)
			(end 0.299974 -0.150114)
			(stroke
				(width 0.1)
				(type default)
			)
			(layer "F.Fab")
		)
		(pad "1" smd rect
			(at -0.2667 0 180)
			(size 0.3048 0.381)
			(layers "F.Cu" "F.Mask" "F.Paste")
			(net "P5E_CPU0_P1_TX_C_DP<0>")
		)
		(pad "2" smd rect
			(at 0.2667 0 180)
			(size 0.3048 0.381)
			(layers "F.Cu" "F.Mask" "F.Paste")
			(net "P5E_CPU0_P1_TX_DP<0>")
		)
	)
	(footprint ""
		(layer "F.Cu")
		(at 205.693518 -143.112998 90)
		(property "Reference" "R2529"
			(at 0 0 90)
			(layer "F.SilkS")
			(hide yes)
			(effects
				(font
					(size 1.27 1.27)
				)
			)
		)
		(property "Value" ""
			(at 0 0 90)
			(layer "F.Fab")
			(effects
				(font
					(size 1.27 1.27)
				)
			)
		)
		(duplicate_pad_numbers_are_jumpers no)
		(fp_line
			(start 0.7874 -0.4064)
			(end 0.7874 0.4064)
			(stroke
				(width 0.1524)
				(type default)
			)
			(layer "F.SilkS")
		)
		(fp_line
			(start -0.7874 -0.4064)
			(end 0.7874 -0.4064)
			(stroke
				(width 0.1524)
				(type default)
			)
			(layer "F.SilkS")
		)
		(fp_line
			(start 0.7874 0.4064)
			(end -0.7874 0.4064)
			(stroke
				(width 0.1524)
				(type default)
			)
			(layer "F.SilkS")
		)
		(fp_line
			(start -0.7874 0.4064)
			(end -0.7874 -0.4064)
			(stroke
				(width 0.1524)
				(type default)
			)
			(layer "F.SilkS")
		)
		(fp_line
			(start -0.12065 -0.305054)
			(end -0.12065 -0.2794)
			(stroke
				(width 0.1)
				(type default)
			)
			(layer "F.Fab")
		)
		(fp_line
			(start -0.67945 -0.305054)
			(end -0.12065 -0.305054)
			(stroke
				(width 0.1)
				(type default)
			)
			(layer "F.Fab")
		)
		(fp_line
			(start 0.67945 -0.3048)
			(end 0.67945 0.3048)
			(stroke
				(width 0.1)
				(type default)
			)
			(layer "F.Fab")
		)
		(fp_line
			(start 0.12065 -0.3048)
			(end 0.67945 -0.3048)
			(stroke
				(width 0.1)
				(type default)
			)
			(layer "F.Fab")
		)
		(fp_line
			(start 0.12065 -0.2794)
			(end 0.12065 -0.3048)
			(stroke
				(width 0.1)
				(type default)
			)
			(layer "F.Fab")
		)
		(fp_line
			(start -0.12065 -0.2794)
			(end 0.12065 -0.2794)
			(stroke
				(width 0.1)
				(type default)
			)
			(layer "F.Fab")
		)
		(fp_line
			(start 0.120396 0.2794)
			(end -0.12065 0.2794)
			(stroke
				(width 0.1)
				(type default)
			)
			(layer "F.Fab")
		)
		(fp_line
			(start -0.12065 0.2794)
			(end -0.12065 0.3048)
			(stroke
				(width 0.1)
				(type default)
			)
			(layer "F.Fab")
		)
		(fp_line
			(start 0.67945 0.3048)
			(end 0.120396 0.3048)
			(stroke
				(width 0.1)
				(type default)
			)
			(layer "F.Fab")
		)
		(fp_line
			(start 0.120396 0.3048)
			(end 0.120396 0.2794)
			(stroke
				(width 0.1)
				(type default)
			)
			(layer "F.Fab")
		)
		(fp_line
			(start -0.12065 0.3048)
			(end -0.67945 0.3048)
			(stroke
				(width 0.1)
				(type default)
			)
			(layer "F.Fab")
		)
		(fp_line
			(start -0.67945 0.3048)
			(end -0.67945 -0.305054)
			(stroke
				(width 0.1)
				(type default)
			)
			(layer "F.Fab")
		)
		(pad "1" smd circle
			(at -0.40005 0 90)
			(size 0 0)
			(layers "F.Cu" "F.Mask" "F.Paste")
			(net "FM_P12V_HSC_EN_N")
		)
		(pad "2" smd circle
			(at 0.40005 0 90)
			(size 0 0)
			(layers "F.Cu" "F.Mask" "F.Paste")
			(net "FM_P12V_HSC_EN_R_N")
		)
	)
	(footprint ""
		(layer "F.Cu")
		(at 188.143642 -413.64408 90)
		(property "Reference" "R9012"
			(at 0 0 90)
			(layer "F.SilkS")
			(hide yes)
			(effects
				(font
					(size 1.27 1.27)
				)
			)
		)
		(property "Value" ""
			(at 0 0 90)
			(layer "F.Fab")
			(effects
				(font
					(size 1.27 1.27)
				)
			)
		)
		(duplicate_pad_numbers_are_jumpers no)
		(fp_line
			(start 0.7874 -0.4064)
			(end 0.7874 0.4064)
			(stroke
				(width 0.1524)
				(type default)
			)
			(layer "F.SilkS")
		)
		(fp_line
			(start -0.7874 -0.4064)
			(end 0.7874 -0.4064)
			(stroke
				(width 0.1524)
				(type default)
			)
			(layer "F.SilkS")
		)
		(fp_line
			(start 0.7874 0.4064)
			(end -0.7874 0.4064)
			(stroke
				(width 0.1524)
				(type default)
			)
			(layer "F.SilkS")
		)
		(fp_line
			(start -0.7874 0.4064)
			(end -0.7874 -0.4064)
			(stroke
				(width 0.1524)
				(type default)
			)
			(layer "F.SilkS")
		)
		(fp_line
			(start -0.12065 -0.305054)
			(end -0.12065 -0.2794)
			(stroke
				(width 0.1)
				(type default)
			)
			(layer "F.Fab")
		)
		(fp_line
			(start -0.67945 -0.305054)
			(end -0.12065 -0.305054)
			(stroke
				(width 0.1)
				(type default)
			)
			(layer "F.Fab")
		)
		(fp_line
			(start 0.67945 -0.3048)
			(end 0.67945 0.3048)
			(stroke
				(width 0.1)
				(type default)
			)
			(layer "F.Fab")
		)
		(fp_line
			(start 0.12065 -0.3048)
			(end 0.67945 -0.3048)
			(stroke
				(width 0.1)
				(type default)
			)
			(layer "F.Fab")
		)
		(fp_line
			(start 0.12065 -0.2794)
			(end 0.12065 -0.3048)
			(stroke
				(width 0.1)
				(type default)
			)
			(layer "F.Fab")
		)
		(fp_line
			(start -0.12065 -0.2794)
			(end 0.12065 -0.2794)
			(stroke
				(width 0.1)
				(type default)
			)
			(layer "F.Fab")
		)
		(fp_line
			(start 0.120396 0.2794)
			(end -0.12065 0.2794)
			(stroke
				(width 0.1)
				(type default)
			)
			(layer "F.Fab")
		)
		(fp_line
			(start -0.12065 0.2794)
			(end -0.12065 0.3048)
			(stroke
				(width 0.1)
				(type default)
			)
			(layer "F.Fab")
		)
		(fp_line
			(start 0.67945 0.3048)
			(end 0.120396 0.3048)
			(stroke
				(width 0.1)
				(type default)
			)
			(layer "F.Fab")
		)
		(fp_line
			(start 0.120396 0.3048)
			(end 0.120396 0.2794)
			(stroke
				(width 0.1)
				(type default)
			)
			(layer "F.Fab")
		)
		(fp_line
			(start -0.12065 0.3048)
			(end -0.67945 0.3048)
			(stroke
				(width 0.1)
				(type default)
			)
			(layer "F.Fab")
		)
		(fp_line
			(start -0.67945 0.3048)
			(end -0.67945 -0.305054)
			(stroke
				(width 0.1)
				(type default)
			)
			(layer "F.Fab")
		)
		(pad "1" smd circle
			(at -0.40005 0 90)
			(size 0 0)
			(layers "F.Cu" "F.Mask" "F.Paste")
			(net "PRSNT_CABLE_SWB_B2_ISO_N")
		)
		(pad "2" smd circle
			(at 0.40005 0 90)
			(size 0 0)
			(layers "F.Cu" "F.Mask" "F.Paste")
			(net "PRSNT_CABLE_SWB_B2_ISO_R_N")
		)
	)
)
